# T6G (Grand Teton) — schematic netlist excerpt (pin names and nets, part order shuffled) for the footprints in the layout excerpt that follows; sources: Cadence DE-HDL packaged netlist, KiCad conversion of 04192023_DAF0TMB3IC0_F0TG_MB_C_brd_V02_OCP.brd

PC616  Q_CAP  2.2UF 10V 10% X6S  pkg C0402  page 223 : A = PVDDIO_P1_VCC4 ; B = GND
PR292  Q_RES  681 1% CHIP  pkg 0402LF  page 193 : A = PVDDCR_SOC_P0_EN//ADDR_CFG ; B = GND
PC2220  Q_CAP  10UF 16V 10% X6S  pkg C0805  page 146 : A = P3V3_E1S_0_R ; B = GND

(kicad_pcb
	(version 20260206)
	(generator "pcbnew")
	(generator_version "10.0")
	(general
		(thickness 1.6)
		(legacy_teardrops no)
	)
	(paper "A4")
	(title_block
		(title "04192023_DAF0TMB3IC0_F0TG_MB_C_brd_V02_OCP.brd")
		(comment 1 "Grand Teton / footprints 3021-3023 of 8354")
	)
	(layers
		(0 "F.Cu" signal "TOP")
		(4 "In1.Cu" signal "GND")
		(6 "In2.Cu" signal "IN1")
		(8 "In3.Cu" signal "GND1")
		(10 "In4.Cu" signal "IN2")
		(12 "In5.Cu" signal "GND2")
		(14 "In6.Cu" signal "IN3")
		(16 "In7.Cu" signal "GND3")
		(18 "In8.Cu" signal "VCC")
		(20 "In9.Cu" signal "VCC1")
		(22 "In10.Cu" signal "GND4")
		(24 "In11.Cu" signal "IN4")
		(26 "In12.Cu" signal "GND5")
		(28 "In13.Cu" signal "IN5")
		(30 "In14.Cu" signal "GND6")
		(32 "In15.Cu" signal "IN6")
		(34 "In16.Cu" signal "GND7")
		(2 "B.Cu" signal "BOTTOM")
		(9 "F.Adhes" user "F.Adhesive")
		(11 "B.Adhes" user "B.Adhesive")
		(13 "F.Paste" user "Package Geometry/Pastemask Top")
		(15 "B.Paste" user "Package Geometry/Pastemask Bottom")
		(5 "F.SilkS" user "Ref Des/Silkscreen Top")
		(7 "B.SilkS" user "Ref Des/Silkscreen Bottom")
		(1 "F.Mask" user "Board Geometry/Soldermask Top")
		(3 "B.Mask" user "Board Geometry/Soldermask Bottom")
		(17 "Dwgs.User" user "User.Drawings")
		(19 "Cmts.User" user "User.Comments")
		(21 "Eco1.User" user "User.Eco1")
		(23 "Eco2.User" user "User.Eco2")
		(25 "Edge.Cuts" user "Board Geometry/Outline")
		(27 "Margin" user)
		(31 "F.CrtYd" user "Package Geometry/Place Bound Top")
		(29 "B.CrtYd" user "Package Geometry/Place Bound Bottom")
		(35 "F.Fab" user "Ref Des/Assembly Top")
		(33 "B.Fab" user "Ref Des/Assembly Bottom")
	)
	(footprint ""
		(layer "F.Cu")
		(at 218.205304 -59.453272 180)
		(property "Reference" "PC2220"
			(at 0 0 180)
			(layer "F.SilkS")
			(hide yes)
			(effects
				(font
					(size 1.27 1.27)
				)
			)
		)
		(property "Value" ""
			(at 0 0 180)
			(layer "F.Fab")
			(effects
				(font
					(size 1.27 1.27)
				)
			)
		)
		(duplicate_pad_numbers_are_jumpers no)
		(fp_line
			(start 1.524 0.762)
			(end -1.524 0.762)
			(stroke
				(width 0.1524)
				(type default)
			)
			(layer "F.SilkS")
		)
		(fp_line
			(start 1.524 -0.762)
			(end 1.524 0.762)
			(stroke
				(width 0.1524)
				(type default)
			)
			(layer "F.SilkS")
		)
		(fp_line
			(start -1.524 0.762)
			(end -1.524 -0.762)
			(stroke
				(width 0.1524)
				(type default)
			)
			(layer "F.SilkS")
		)
		(fp_line
			(start -1.524 -0.762)
			(end 1.524 -0.762)
			(stroke
				(width 0.1524)
				(type default)
			)
			(layer "F.SilkS")
		)
		(fp_line
			(start 1.1049 0.724916)
			(end 1.1049 -0.724916)
			(stroke
				(width 0.1)
				(type default)
			)
			(layer "F.Fab")
		)
		(fp_line
			(start 1.1049 -0.724916)
			(end -1.1049 -0.724916)
			(stroke
				(width 0.1)
				(type default)
			)
			(layer "F.Fab")
		)
		(fp_line
			(start -1.1049 0.724916)
			(end 1.1049 0.724916)
			(stroke
				(width 0.1)
				(type default)
			)
			(layer "F.Fab")
		)
		(fp_line
			(start -1.1049 -0.724916)
			(end -1.1049 0.724916)
			(stroke
				(width 0.1)
				(type default)
			)
			(layer "F.Fab")
		)
		(pad "1" smd rect
			(at -0.889 0)
			(size 1.016 1.27)
			(layers "F.Cu" "F.Mask" "F.Paste")
			(net "P3V3_E1S_0_R")
		)
		(pad "2" smd rect
			(at 0.889 0)
			(size 1.016 1.27)
			(layers "F.Cu" "F.Mask" "F.Paste")
			(net "GND")
		)
	)
	(footprint ""
		(layer "F.Cu")
		(at 381.598678 -142.665958 180)
		(property "Reference" "PR292"
			(at 0 0 180)
			(layer "F.SilkS")
			(hide yes)
			(effects
				(font
					(size 1.27 1.27)
				)
			)
		)
		(property "Value" ""
			(at 0 0 180)
			(layer "F.Fab")
			(effects
				(font
					(size 1.27 1.27)
				)
			)
		)
		(duplicate_pad_numbers_are_jumpers no)
		(fp_line
			(start 0.7874 0.4064)
			(end -0.7874 0.4064)
			(stroke
				(width 0.1524)
				(type default)
			)
			(layer "F.SilkS")
		)
		(fp_line
			(start 0.7874 -0.4064)
			(end 0.7874 0.4064)
			(stroke
				(width 0.1524)
				(type default)
			)
			(layer "F.SilkS")
		)
		(fp_line
			(start -0.7874 0.4064)
			(end -0.7874 -0.4064)
			(stroke
				(width 0.1524)
				(type default)
			)
			(layer "F.SilkS")
		)
		(fp_line
			(start -0.7874 -0.4064)
			(end 0.7874 -0.4064)
			(stroke
				(width 0.1524)
				(type default)
			)
			(layer "F.SilkS")
		)
		(fp_line
			(start 0.67945 0.3048)
			(end 0.120396 0.3048)
			(stroke
				(width 0.1)
				(type default)
			)
			(layer "F.Fab")
		)
		(fp_line
			(start 0.67945 -0.3048)
			(end 0.67945 0.3048)
			(stroke
				(width 0.1)
				(type default)
			)
			(layer "F.Fab")
		)
		(fp_line
			(start 0.12065 -0.2794)
			(end 0.12065 -0.3048)
			(stroke
				(width 0.1)
				(type default)
			)
			(layer "F.Fab")
		)
		(fp_line
			(start 0.12065 -0.3048)
			(end 0.67945 -0.3048)
			(stroke
				(width 0.1)
				(type default)
			)
			(layer "F.Fab")
		)
		(fp_line
			(start 0.120396 0.3048)
			(end 0.120396 0.2794)
			(stroke
				(width 0.1)
				(type default)
			)
			(layer "F.Fab")
		)
		(fp_line
			(start 0.120396 0.2794)
			(end -0.12065 0.2794)
			(stroke
				(width 0.1)
				(type default)
			)
			(layer "F.Fab")
		)
		(fp_line
			(start -0.12065 0.3048)
			(end -0.67945 0.3048)
			(stroke
				(width 0.1)
				(type default)
			)
			(layer "F.Fab")
		)
		(fp_line
			(start -0.12065 0.2794)
			(end -0.12065 0.3048)
			(stroke
				(width 0.1)
				(type default)
			)
			(layer "F.Fab")
		)
		(fp_line
			(start -0.12065 -0.2794)
			(end 0.12065 -0.2794)
			(stroke
				(width 0.1)
				(type default)
			)
			(layer "F.Fab")
		)
		(fp_line
			(start -0.12065 -0.305054)
			(end -0.12065 -0.2794)
			(stroke
				(width 0.1)
				(type default)
			)
			(layer "F.Fab")
		)
		(fp_line
			(start -0.67945 0.3048)
			(end -0.67945 -0.305054)
			(stroke
				(width 0.1)
				(type default)
			)
			(layer "F.Fab")
		)
		(fp_line
			(start -0.67945 -0.305054)
			(end -0.12065 -0.305054)
			(stroke
				(width 0.1)
				(type default)
			)
			(layer "F.Fab")
		)
		(pad "1" smd circle
			(at -0.40005 0 180)
			(size 0 0)
			(layers "F.Cu" "F.Mask" "F.Paste")
			(net "PVDDCR_SOC_P0_EN//ADDR_CFG")
		)
		(pad "2" smd circle
			(at 0.40005 0 180)
			(size 0 0)
			(layers "F.Cu" "F.Mask" "F.Paste")
			(net "GND")
		)
	)
	(footprint ""
		(layer "F.Cu")
		(at 24.917654 -349.386398 90)
		(property "Reference" "PC616"
			(at 0 0 90)
			(layer "F.SilkS")
			(hide yes)
			(effects
				(font
					(size 1.27 1.27)
				)
			)
		)
		(property "Value" ""
			(at 0 0 90)
			(layer "F.Fab")
			(effects
				(font
					(size 1.27 1.27)
				)
			)
		)
		(duplicate_pad_numbers_are_jumpers no)
		(fp_line
			(start 0.7874 -0.4064)
			(end 0.7874 0.4064)
			(stroke
				(width 0.1524)
				(type default)
			)
			(layer "F.SilkS")
		)
		(fp_line
			(start -0.7874 -0.4064)
			(end 0.7874 -0.4064)
			(stroke
				(width 0.1524)
				(type default)
			)
			(layer "F.SilkS")
		)
		(fp_line
			(start 0.7874 0.4064)
			(end 0.498602 0.4064)
			(stroke
				(width 0.1524)
				(type default)
			)
			(layer "F.SilkS")
		)
		(fp_line
			(start -0.314198 0.4064)
			(end -0.7874 0.4064)
			(stroke
				(width 0.1524)
				(type default)
			)
			(layer "F.SilkS")
		)
		(fp_line
			(start -0.7874 0.4064)
			(end -0.7874 -0.4064)
			(stroke
				(width 0.1524)
				(type default)
			)
			(layer "F.SilkS")
		)
		(fp_line
			(start -0.12065 -0.305054)
			(end -0.12065 -0.2794)
			(stroke
				(width 0.1)
				(type default)
			)
			(layer "F.Fab")
		)
		(fp_line
			(start -0.67945 -0.305054)
			(end -0.12065 -0.305054)
			(stroke
				(width 0.1)
				(type default)
			)
			(layer "F.Fab")
		)
		(fp_line
			(start 0.67945 -0.3048)
			(end 0.67945 0.3048)
			(stroke
				(width 0.1)
				(type default)
			)
			(layer "F.Fab")
		)
		(fp_line
			(start 0.12065 -0.3048)
			(end 0.67945 -0.3048)
			(stroke
				(width 0.1)
				(type default)
			)
			(layer "F.Fab")
		)
		(fp_line
			(start 0.12065 -0.2794)
			(end 0.12065 -0.3048)
			(stroke
				(width 0.1)
				(type default)
			)
			(layer "F.Fab")
		)
		(fp_line
			(start -0.12065 -0.2794)
			(end 0.12065 -0.2794)
			(stroke
				(width 0.1)
				(type default)
			)
			(layer "F.Fab")
		)
		(fp_line
			(start 0.120396 0.2794)
			(end -0.12065 0.2794)
			(stroke
				(width 0.1)
				(type default)
			)
			(layer "F.Fab")
		)
		(fp_line
			(start -0.12065 0.2794)
			(end -0.12065 0.3048)
			(stroke
				(width 0.1)
				(type default)
			)
			(layer "F.Fab")
		)
		(fp_line
			(start 0.67945 0.3048)
			(end 0.120396 0.3048)
			(stroke
				(width 0.1)
				(type default)
			)
			(layer "F.Fab")
		)
		(fp_line
			(start 0.120396 0.3048)
			(end 0.120396 0.2794)
			(stroke
				(width 0.1)
				(type default)
			)
			(layer "F.Fab")
		)
		(fp_line
			(start -0.12065 0.3048)
			(end -0.67945 0.3048)
			(stroke
				(width 0.1)
				(type default)
			)
			(layer "F.Fab")
		)
		(fp_line
			(start -0.67945 0.3048)
			(end -0.67945 -0.305054)
			(stroke
				(width 0.1)
				(type default)
			)
			(layer "F.Fab")
		)
		(pad "1" smd circle
			(at -0.40005 0 90)
			(size 0 0)
			(layers "F.Cu" "F.Mask" "F.Paste")
			(net "PVDDIO_P1_VCC4")
		)
		(pad "2" smd circle
			(at 0.40005 0 90)
			(size 0 0)
			(layers "F.Cu" "F.Mask" "F.Paste")
			(net "GND")
		)
	)
)
